# T6G (Grand Teton) — schematic netlist excerpt (pin names and nets, part order shuffled) for the footprints in the layout excerpt that follows; sources: Cadence DE-HDL packaged netlist, KiCad conversion of 04192023_DAF0TMB3IC0_F0TG_MB_C_brd_V02_OCP.brd

C2150  Q_CAP  22UF 4V 20% X6S  pkg C0402  page 68 : A = PVDD11_S3_P0 ; B = GND
R4550  Q_RES  49.9 1% CHIP  pkg 0402LF  page 124 : A = SWB_HSC_EN_BUF_R ; B = SWB_HSC_EN_BUF

(kicad_pcb
	(version 20260206)
	(generator "pcbnew")
	(generator_version "10.0")
	(general
		(thickness 1.6)
		(legacy_teardrops no)
	)
	(paper "A4")
	(title_block
		(title "04192023_DAF0TMB3IC0_F0TG_MB_C_brd_V02_OCP.brd")
		(comment 1 "Grand Teton / footprints 4658-4659 of 8354")
	)
	(layers
		(0 "F.Cu" signal "TOP")
		(4 "In1.Cu" signal "GND")
		(6 "In2.Cu" signal "IN1")
		(8 "In3.Cu" signal "GND1")
		(10 "In4.Cu" signal "IN2")
		(12 "In5.Cu" signal "GND2")
		(14 "In6.Cu" signal "IN3")
		(16 "In7.Cu" signal "GND3")
		(18 "In8.Cu" signal "VCC")
		(20 "In9.Cu" signal "VCC1")
		(22 "In10.Cu" signal "GND4")
		(24 "In11.Cu" signal "IN4")
		(26 "In12.Cu" signal "GND5")
		(28 "In13.Cu" signal "IN5")
		(30 "In14.Cu" signal "GND6")
		(32 "In15.Cu" signal "IN6")
		(34 "In16.Cu" signal "GND7")
		(2 "B.Cu" signal "BOTTOM")
		(9 "F.Adhes" user "F.Adhesive")
		(11 "B.Adhes" user "B.Adhesive")
		(13 "F.Paste" user "Package Geometry/Pastemask Top")
		(15 "B.Paste" user "Package Geometry/Pastemask Bottom")
		(5 "F.SilkS" user "Ref Des/Silkscreen Top")
		(7 "B.SilkS" user "Ref Des/Silkscreen Bottom")
		(1 "F.Mask" user "Board Geometry/Soldermask Top")
		(3 "B.Mask" user "Board Geometry/Soldermask Bottom")
		(17 "Dwgs.User" user "User.Drawings")
		(19 "Cmts.User" user "User.Comments")
		(21 "Eco1.User" user "User.Eco1")
		(23 "Eco2.User" user "User.Eco2")
		(25 "Edge.Cuts" user "Board Geometry/Outline")
		(27 "Margin" user)
		(31 "F.CrtYd" user "Package Geometry/Place Bound Top")
		(29 "B.CrtYd" user "Package Geometry/Place Bound Bottom")
		(35 "F.Fab" user "Ref Des/Assembly Top")
		(33 "B.Fab" user "Ref Des/Assembly Bottom")
	)
	(footprint ""
		(layer "F.Cu")
		(at 355.617272 -261.747762 -90)
		(property "Reference" "C2150"
			(at 0 0 270)
			(layer "F.SilkS")
			(hide yes)
			(effects
				(font
					(size 1.27 1.27)
				)
			)
		)
		(property "Value" ""
			(at 0 0 270)
			(layer "F.Fab")
			(effects
				(font
					(size 1.27 1.27)
				)
			)
		)
		(duplicate_pad_numbers_are_jumpers no)
		(fp_line
			(start -0.7874 0.4064)
			(end -0.7874 -0.4064)
			(stroke
				(width 0.1524)
				(type default)
			)
			(layer "F.SilkS")
		)
		(fp_line
			(start 0.7874 0.4064)
			(end -0.7874 0.4064)
			(stroke
				(width 0.1524)
				(type default)
			)
			(layer "F.SilkS")
		)
		(fp_line
			(start -0.7874 -0.4064)
			(end 0.7874 -0.4064)
			(stroke
				(width 0.1524)
				(type default)
			)
			(layer "F.SilkS")
		)
		(fp_line
			(start 0.7874 -0.4064)
			(end 0.7874 0.4064)
			(stroke
				(width 0.1524)
				(type default)
			)
			(layer "F.SilkS")
		)
		(fp_line
			(start -0.67945 0.3048)
			(end -0.67945 -0.305054)
			(stroke
				(width 0.1)
				(type default)
			)
			(layer "F.Fab")
		)
		(fp_line
			(start -0.12065 0.3048)
			(end -0.67945 0.3048)
			(stroke
				(width 0.1)
				(type default)
			)
			(layer "F.Fab")
		)
		(fp_line
			(start 0.120396 0.3048)
			(end 0.120396 0.2794)
			(stroke
				(width 0.1)
				(type default)
			)
			(layer "F.Fab")
		)
		(fp_line
			(start 0.67945 0.3048)
			(end 0.120396 0.3048)
			(stroke
				(width 0.1)
				(type default)
			)
			(layer "F.Fab")
		)
		(fp_line
			(start -0.12065 0.2794)
			(end -0.12065 0.3048)
			(stroke
				(width 0.1)
				(type default)
			)
			(layer "F.Fab")
		)
		(fp_line
			(start 0.120396 0.2794)
			(end -0.12065 0.2794)
			(stroke
				(width 0.1)
				(type default)
			)
			(layer "F.Fab")
		)
		(fp_line
			(start -0.12065 -0.2794)
			(end 0.12065 -0.2794)
			(stroke
				(width 0.1)
				(type default)
			)
			(layer "F.Fab")
		)
		(fp_line
			(start 0.12065 -0.2794)
			(end 0.12065 -0.3048)
			(stroke
				(width 0.1)
				(type default)
			)
			(layer "F.Fab")
		)
		(fp_line
			(start 0.12065 -0.3048)
			(end 0.67945 -0.3048)
			(stroke
				(width 0.1)
				(type default)
			)
			(layer "F.Fab")
		)
		(fp_line
			(start 0.67945 -0.3048)
			(end 0.67945 0.3048)
			(stroke
				(width 0.1)
				(type default)
			)
			(layer "F.Fab")
		)
		(fp_line
			(start -0.67945 -0.305054)
			(end -0.12065 -0.305054)
			(stroke
				(width 0.1)
				(type default)
			)
			(layer "F.Fab")
		)
		(fp_line
			(start -0.12065 -0.305054)
			(end -0.12065 -0.2794)
			(stroke
				(width 0.1)
				(type default)
			)
			(layer "F.Fab")
		)
		(pad "1" smd circle
			(at -0.40005 0 270)
			(size 0 0)
			(layers "F.Cu" "F.Mask" "F.Paste")
			(net "PVDD11_S3_P0")
		)
		(pad "2" smd circle
			(at 0.40005 0 270)
			(size 0 0)
			(layers "F.Cu" "F.Mask" "F.Paste")
			(net "GND")
		)
	)
	(footprint ""
		(layer "F.Cu")
		(at 352.05543 -431.809652 180)
		(property "Reference" "R4550"
			(at 0 0 180)
			(layer "F.SilkS")
			(hide yes)
			(effects
				(font
					(size 1.27 1.27)
				)
			)
		)
		(property "Value" ""
			(at 0 0 180)
			(layer "F.Fab")
			(effects
				(font
					(size 1.27 1.27)
				)
			)
		)
		(duplicate_pad_numbers_are_jumpers no)
		(fp_line
			(start 0.7874 0.4064)
			(end -0.7874 0.4064)
			(stroke
				(width 0.1524)
				(type default)
			)
			(layer "F.SilkS")
		)
		(fp_line
			(start 0.7874 -0.4064)
			(end 0.7874 0.4064)
			(stroke
				(width 0.1524)
				(type default)
			)
			(layer "F.SilkS")
		)
		(fp_line
			(start -0.7874 0.4064)
			(end -0.7874 -0.4064)
			(stroke
				(width 0.1524)
				(type default)
			)
			(layer "F.SilkS")
		)
		(fp_line
			(start -0.7874 -0.4064)
			(end 0.7874 -0.4064)
			(stroke
				(width 0.1524)
				(type default)
			)
			(layer "F.SilkS")
		)
		(fp_line
			(start 0.67945 0.3048)
			(end 0.120396 0.3048)
			(stroke
				(width 0.1)
				(type default)
			)
			(layer "F.Fab")
		)
		(fp_line
			(start 0.67945 -0.3048)
			(end 0.67945 0.3048)
			(stroke
				(width 0.1)
				(type default)
			)
			(layer "F.Fab")
		)
		(fp_line
			(start 0.12065 -0.2794)
			(end 0.12065 -0.3048)
			(stroke
				(width 0.1)
				(type default)
			)
			(layer "F.Fab")
		)
		(fp_line
			(start 0.12065 -0.3048)
			(end 0.67945 -0.3048)
			(stroke
				(width 0.1)
				(type default)
			)
			(layer "F.Fab")
		)
		(fp_line
			(start 0.120396 0.3048)
			(end 0.120396 0.2794)
			(stroke
				(width 0.1)
				(type default)
			)
			(layer "F.Fab")
		)
		(fp_line
			(start 0.120396 0.2794)
			(end -0.12065 0.2794)
			(stroke
				(width 0.1)
				(type default)
			)
			(layer "F.Fab")
		)
		(fp_line
			(start -0.12065 0.3048)
			(end -0.67945 0.3048)
			(stroke
				(width 0.1)
				(type default)
			)
			(layer "F.Fab")
		)
		(fp_line
			(start -0.12065 0.2794)
			(end -0.12065 0.3048)
			(stroke
				(width 0.1)
				(type default)
			)
			(layer "F.Fab")
		)
		(fp_line
			(start -0.12065 -0.2794)
			(end 0.12065 -0.2794)
			(stroke
				(width 0.1)
				(type default)
			)
			(layer "F.Fab")
		)
		(fp_line
			(start -0.12065 -0.305054)
			(end -0.12065 -0.2794)
			(stroke
				(width 0.1)
				(type default)
			)
			(layer "F.Fab")
		)
		(fp_line
			(start -0.67945 0.3048)
			(end -0.67945 -0.305054)
			(stroke
				(width 0.1)
				(type default)
			)
			(layer "F.Fab")
		)
		(fp_line
			(start -0.67945 -0.305054)
			(end -0.12065 -0.305054)
			(stroke
				(width 0.1)
				(type default)
			)
			(layer "F.Fab")
		)
		(pad "1" smd circle
			(at -0.40005 0 180)
			(size 0 0)
			(layers "F.Cu" "F.Mask" "F.Paste")
			(net "SWB_HSC_EN_BUF_R")
		)
		(pad "2" smd circle
			(at 0.40005 0 180)
			(size 0 0)
			(layers "F.Cu" "F.Mask" "F.Paste")
			(net "SWB_HSC_EN_BUF")
		)
	)
)
